# T6G (Grand Teton) — schematic netlist excerpt (pin names and nets, part order shuffled) for the footprints in the layout excerpt that follows; sources: Cadence DE-HDL packaged netlist, KiCad conversion of 04192023_DAF0TMB3IC0_F0TG_MB_C_brd_V02_OCP.brd

C1051  Q_CAP  0.1UF 10V 10% X7S  pkg C0201  page 312 : A = P0V9_CPU0_RT3_2A ; B = GND
C2199  Q_CAP  22UF 4V 20% X6S  pkg C0402  page 69 : A = PVDDCR_CPU0_P0 ; B = GND
R976  Q_RES  0 5% CHIP  pkg 0201LF  page 276 : A = SMB_RT_CPU0_P0_R_SCL ; B = SMB_RT_CPU0_P0_R2_SCL

(kicad_pcb
	(version 20260206)
	(generator "pcbnew")
	(generator_version "10.0")
	(general
		(thickness 1.6)
		(legacy_teardrops no)
	)
	(paper "A4")
	(title_block
		(title "04192023_DAF0TMB3IC0_F0TG_MB_C_brd_V02_OCP.brd")
		(comment 1 "Grand Teton / footprints 6022-6024 of 8354")
	)
	(layers
		(0 "F.Cu" signal "TOP")
		(4 "In1.Cu" signal "GND")
		(6 "In2.Cu" signal "IN1")
		(8 "In3.Cu" signal "GND1")
		(10 "In4.Cu" signal "IN2")
		(12 "In5.Cu" signal "GND2")
		(14 "In6.Cu" signal "IN3")
		(16 "In7.Cu" signal "GND3")
		(18 "In8.Cu" signal "VCC")
		(20 "In9.Cu" signal "VCC1")
		(22 "In10.Cu" signal "GND4")
		(24 "In11.Cu" signal "IN4")
		(26 "In12.Cu" signal "GND5")
		(28 "In13.Cu" signal "IN5")
		(30 "In14.Cu" signal "GND6")
		(32 "In15.Cu" signal "IN6")
		(34 "In16.Cu" signal "GND7")
		(2 "B.Cu" signal "BOTTOM")
		(9 "F.Adhes" user "F.Adhesive")
		(11 "B.Adhes" user "B.Adhesive")
		(13 "F.Paste" user "Package Geometry/Pastemask Top")
		(15 "B.Paste" user "Package Geometry/Pastemask Bottom")
		(5 "F.SilkS" user "Ref Des/Silkscreen Top")
		(7 "B.SilkS" user "Ref Des/Silkscreen Bottom")
		(1 "F.Mask" user "Board Geometry/Soldermask Top")
		(3 "B.Mask" user "Board Geometry/Soldermask Bottom")
		(17 "Dwgs.User" user "User.Drawings")
		(19 "Cmts.User" user "User.Comments")
		(21 "Eco1.User" user "User.Eco1")
		(23 "Eco2.User" user "User.Eco2")
		(25 "Edge.Cuts" user "Board Geometry/Outline")
		(27 "Margin" user)
		(31 "F.CrtYd" user "Package Geometry/Place Bound Top")
		(29 "B.CrtYd" user "Package Geometry/Place Bound Bottom")
		(35 "F.Fab" user "Ref Des/Assembly Top")
		(33 "B.Fab" user "Ref Des/Assembly Bottom")
	)
	(footprint ""
		(layer "B.Cu")
		(at 356.406958 -246.376952)
		(property "Reference" "C2199"
			(at 0 0 0)
			(layer "B.SilkS")
			(hide yes)
			(effects
				(font
					(size 1.27 1.27)
				)
				(justify mirror)
			)
		)
		(property "Value" ""
			(at 0 0 0)
			(layer "B.Fab")
			(effects
				(font
					(size 1.27 1.27)
				)
				(justify mirror)
			)
		)
		(duplicate_pad_numbers_are_jumpers no)
		(fp_line
			(start -0.7874 -0.4064)
			(end -0.7874 0.4064)
			(stroke
				(width 0.1524)
				(type default)
			)
			(layer "B.SilkS")
		)
		(fp_line
			(start -0.7874 0.4064)
			(end 0.7874 0.4064)
			(stroke
				(width 0.1524)
				(type default)
			)
			(layer "B.SilkS")
		)
		(fp_line
			(start 0.7874 -0.4064)
			(end -0.7874 -0.4064)
			(stroke
				(width 0.1524)
				(type default)
			)
			(layer "B.SilkS")
		)
		(fp_line
			(start 0.7874 0.4064)
			(end 0.7874 -0.4064)
			(stroke
				(width 0.1524)
				(type default)
			)
			(layer "B.SilkS")
		)
		(fp_line
			(start -0.67945 -0.3048)
			(end -0.67945 0.3048)
			(stroke
				(width 0.1)
				(type default)
			)
			(layer "B.Fab")
		)
		(fp_line
			(start -0.67945 0.3048)
			(end -0.120396 0.3048)
			(stroke
				(width 0.1)
				(type default)
			)
			(layer "B.Fab")
		)
		(fp_line
			(start -0.12065 -0.3048)
			(end -0.67945 -0.3048)
			(stroke
				(width 0.1)
				(type default)
			)
			(layer "B.Fab")
		)
		(fp_line
			(start -0.12065 -0.2794)
			(end -0.12065 -0.3048)
			(stroke
				(width 0.1)
				(type default)
			)
			(layer "B.Fab")
		)
		(fp_line
			(start -0.120396 0.2794)
			(end 0.12065 0.2794)
			(stroke
				(width 0.1)
				(type default)
			)
			(layer "B.Fab")
		)
		(fp_line
			(start -0.120396 0.3048)
			(end -0.120396 0.2794)
			(stroke
				(width 0.1)
				(type default)
			)
			(layer "B.Fab")
		)
		(fp_line
			(start 0.12065 -0.305054)
			(end 0.12065 -0.2794)
			(stroke
				(width 0.1)
				(type default)
			)
			(layer "B.Fab")
		)
		(fp_line
			(start 0.12065 -0.2794)
			(end -0.12065 -0.2794)
			(stroke
				(width 0.1)
				(type default)
			)
			(layer "B.Fab")
		)
		(fp_line
			(start 0.12065 0.2794)
			(end 0.12065 0.3048)
			(stroke
				(width 0.1)
				(type default)
			)
			(layer "B.Fab")
		)
		(fp_line
			(start 0.12065 0.3048)
			(end 0.67945 0.3048)
			(stroke
				(width 0.1)
				(type default)
			)
			(layer "B.Fab")
		)
		(fp_line
			(start 0.67945 -0.305054)
			(end 0.12065 -0.305054)
			(stroke
				(width 0.1)
				(type default)
			)
			(layer "B.Fab")
		)
		(fp_line
			(start 0.67945 0.3048)
			(end 0.67945 -0.305054)
			(stroke
				(width 0.1)
				(type default)
			)
			(layer "B.Fab")
		)
		(pad "1" smd circle
			(at 0.40005 0 180)
			(size 0 0)
			(layers "B.Cu" "B.Mask" "B.Paste")
			(net "PVDDCR_CPU0_P0")
		)
		(pad "2" smd circle
			(at -0.40005 0 180)
			(size 0 0)
			(layers "B.Cu" "B.Mask" "B.Paste")
			(net "GND")
		)
	)
	(footprint ""
		(layer "B.Cu")
		(at 386.21843 -396.393162 -90)
		(property "Reference" "C1051"
			(at 0 0 90)
			(layer "B.SilkS")
			(hide yes)
			(effects
				(font
					(size 1.27 1.27)
				)
				(justify mirror)
			)
		)
		(property "Value" ""
			(at 0 0 90)
			(layer "B.Fab")
			(effects
				(font
					(size 1.27 1.27)
				)
				(justify mirror)
			)
		)
		(duplicate_pad_numbers_are_jumpers no)
		(fp_line
			(start -0.299974 0.150114)
			(end 0.299974 0.150114)
			(stroke
				(width 0.1)
				(type default)
			)
			(layer "B.Fab")
		)
		(fp_line
			(start 0.299974 0.150114)
			(end 0.299974 -0.150114)
			(stroke
				(width 0.1)
				(type default)
			)
			(layer "B.Fab")
		)
		(fp_line
			(start -0.299974 -0.150114)
			(end -0.299974 0.150114)
			(stroke
				(width 0.1)
				(type default)
			)
			(layer "B.Fab")
		)
		(fp_line
			(start 0.299974 -0.150114)
			(end -0.299974 -0.150114)
			(stroke
				(width 0.1)
				(type default)
			)
			(layer "B.Fab")
		)
		(pad "1" smd rect
			(at 0.2667 0 90)
			(size 0.3048 0.381)
			(layers "B.Cu" "B.Mask" "B.Paste")
			(net "P0V9_CPU0_RT3_2A")
		)
		(pad "2" smd rect
			(at -0.2667 0 90)
			(size 0.3048 0.381)
			(layers "B.Cu" "B.Mask" "B.Paste")
			(net "GND")
		)
	)
	(footprint ""
		(layer "B.Cu")
		(at 233.172 -340.868 180)
		(property "Reference" "R976"
			(at 0 0 0)
			(layer "B.SilkS")
			(hide yes)
			(effects
				(font
					(size 1.27 1.27)
				)
				(justify mirror)
			)
		)
		(property "Value" ""
			(at 0 0 0)
			(layer "B.Fab")
			(effects
				(font
					(size 1.27 1.27)
				)
				(justify mirror)
			)
		)
		(duplicate_pad_numbers_are_jumpers no)
		(fp_line
			(start 0.32512 0.175006)
			(end 0.32512 -0.175006)
			(stroke
				(width 0.1)
				(type default)
			)
			(layer "B.Fab")
		)
		(fp_line
			(start 0.32512 -0.175006)
			(end -0.32512 -0.175006)
			(stroke
				(width 0.1)
				(type default)
			)
			(layer "B.Fab")
		)
		(fp_line
			(start -0.32512 0.175006)
			(end 0.32512 0.175006)
			(stroke
				(width 0.1)
				(type default)
			)
			(layer "B.Fab")
		)
		(fp_line
			(start -0.32512 -0.175006)
			(end -0.32512 0.175006)
			(stroke
				(width 0.1)
				(type default)
			)
			(layer "B.Fab")
		)
		(pad "1" smd rect
			(at 0.2667 0)
			(size 0.3048 0.381)
			(layers "B.Cu" "B.Mask" "B.Paste")
			(net "SMB_RT_CPU0_P0_R_SCL")
		)
		(pad "2" smd rect
			(at -0.2667 0 180)
			(size 0.3048 0.381)
			(layers "B.Cu" "B.Mask" "B.Paste")
			(net "SMB_RT_CPU0_P0_R2_SCL")
		)
	)
)
